(kicad_pcb
	(version 20240108)
	(generator "pcbnew")
	(generator_version "8.0")
	(general
		(thickness 1.62)
		(legacy_teardrops no)
	)
	(paper "A4")
	(title_block
		(title "Jetson Orin Baseboard")
		(date "2025-03-12")
		(rev "1.3.4")
		(company "Antmicro Ltd")
		(comment 1 "www.antmicro.com")
		(comment 9 "footprints 291-295 of 677")
	)
	(layers
		(0 "F.Cu" signal)
		(1 "In1.Cu" signal)
		(2 "In2.Cu" signal)
		(3 "In3.Cu" signal)
		(4 "In4.Cu" jumper)
		(5 "In5.Cu" signal)
		(6 "In6.Cu" signal)
		(31 "B.Cu" signal)
		(32 "B.Adhes" user "B.Adhesive")
		(33 "F.Adhes" user "F.Adhesive")
		(34 "B.Paste" user)
		(35 "F.Paste" user)
		(36 "B.SilkS" user "B.Silkscreen")
		(37 "F.SilkS" user "F.Silkscreen")
		(38 "B.Mask" user)
		(39 "F.Mask" user)
		(40 "Dwgs.User" user "User.Drawings")
		(41 "Cmts.User" user "User.Comments")
		(42 "Eco1.User" user "User.Eco1")
		(43 "Eco2.User" user "User.Eco2")
		(44 "Edge.Cuts" user)
		(45 "Margin" user)
		(46 "B.CrtYd" user "B.Courtyard")
		(47 "F.CrtYd" user "F.Courtyard")
		(48 "B.Fab" user)
		(49 "F.Fab" user)
	)
	(footprint "antmicro-footprints:R_0402_1005Metric"
		(layer "F.Cu")
		(at 136.3 119.7)
		(descr "Resistor SMD 0402")
		(tags "resistor SMD 0402")
		(property "Reference" "R222"
			(at -1.05 -0.4 0)
			(layer "F.SilkS")
			(effects
				(font
					(size 0.7 0.7)
					(thickness 0.15)
				)
				(justify left bottom)
			)
		)
		(property "Value" "R_100k_0402"
			(at 0 1.4 0)
			(layer "F.Fab")
			(effects
				(font
					(size 0.7 0.7)
					(thickness 0.15)
				)
				(justify left bottom)
			)
		)
		(property "Footprint" "antmicro-footprints:R_0402_1005Metric"
			(at 0 0 0)
			(layer "F.Fab")
			(hide yes)
			(effects
				(font
					(size 1.27 1.27)
					(thickness 0.15)
				)
			)
		)
		(property "Datasheet" "https://www.bourns.com/docs/product-datasheets/cr.pdf"
			(at 0 0 0)
			(layer "F.Fab")
			(hide yes)
			(effects
				(font
					(size 1.27 1.27)
					(thickness 0.15)
				)
			)
		)
		(property "Author" "Antmicro"
			(at 0 0 0)
			(layer "F.Fab")
			(hide yes)
			(effects
				(font
					(size 1 1)
					(thickness 0.15)
				)
			)
		)
		(property "License" "Apache-2.0"
			(at 0 0 0)
			(layer "F.Fab")
			(hide yes)
			(effects
				(font
					(size 1 1)
					(thickness 0.15)
				)
			)
		)
		(property "MPN" "CR0402-FX-1003GLF"
			(at 0 0 0)
			(layer "F.Fab")
			(hide yes)
			(effects
				(font
					(size 1 1)
					(thickness 0.15)
				)
			)
		)
		(property "Manufacturer" "Bourns"
			(at 0 0 0)
			(layer "F.Fab")
			(hide yes)
			(effects
				(font
					(size 1 1)
					(thickness 0.15)
				)
			)
		)
		(property "Tolerance" "1%"
			(at 0 0 0)
			(layer "F.Fab")
			(hide yes)
			(effects
				(font
					(size 1 1)
					(thickness 0.15)
				)
			)
		)
		(property "Val" "100k"
			(at 0 0 0)
			(layer "F.Fab")
			(hide yes)
			(effects
				(font
					(size 1 1)
					(thickness 0.15)
				)
			)
		)
		(sheetname "Peripherals")
		(sheetfile "peripherals.kicad_sch")
		(attr smd)
		(fp_rect
			(start -0.925 -0.47)
			(end 0.925 0.47)
			(stroke
				(width 0.05)
				(type default)
			)
			(fill none)
			(layer "F.CrtYd")
		)
		(fp_rect
			(start -0.5 -0.25)
			(end 0.5 0.25)
			(stroke
				(width 0.15)
				(type solid)
			)
			(fill none)
			(layer "F.Fab")
		)
		(fp_text user "${REFERENCE}"
			(at -0.95 3.168 0)
			(layer "F.Fab")
			(hide yes)
			(effects
				(font
					(size 0.7 0.7)
					(thickness 0.15)
				)
				(justify left bottom)
			)
		)
		(fp_text user "License: Apache-2.0"
			(at -0.95 5.169 0)
			(layer "F.Fab")
			(hide yes)
			(effects
				(font
					(size 0.7 0.7)
					(thickness 0.15)
				)
				(justify left bottom)
			)
		)
		(fp_text user "Author: Antmicro"
			(at -0.95 4.169 0)
			(layer "F.Fab")
			(hide yes)
			(effects
				(font
					(size 0.7 0.7)
					(thickness 0.15)
				)
				(justify left bottom)
			)
		)
		(pad "1" smd roundrect
			(at -0.48 0)
			(size 0.59 0.64)
			(layers "F.Cu" "F.Paste" "F.Mask")
			(roundrect_rratio 0.25)
			(net 1 "GND")
			(pintype "passive")
		)
		(pad "2" smd roundrect
			(at 0.48 0)
			(size 0.59 0.64)
			(layers "F.Cu" "F.Paste" "F.Mask")
			(roundrect_rratio 0.25)
			(net 440 "USER_LED0")
			(pintype "passive")
		)
	)
	(footprint "antmicro-footprints:R_0402_1005Metric"
		(layer "F.Cu")
		(at 101.95 87.65 90)
		(descr "Resistor SMD 0402")
		(tags "resistor SMD 0402")
		(property "Reference" "R40"
			(at -1.05 -0.45 90)
			(layer "F.SilkS")
			(effects
				(font
					(size 0.7 0.7)
					(thickness 0.15)
				)
				(justify left bottom)
			)
		)
		(property "Value" "R_0R_0402"
			(at 0 1.4 90)
			(layer "F.Fab")
			(effects
				(font
					(size 0.7 0.7)
					(thickness 0.15)
				)
				(justify left bottom)
			)
		)
		(property "Footprint" "antmicro-footprints:R_0402_1005Metric"
			(at 0 0 90)
			(layer "F.Fab")
			(hide yes)
			(effects
				(font
					(size 1.27 1.27)
					(thickness 0.15)
				)
			)
		)
		(property "Datasheet" "https://industrial.panasonic.com/cdbs/www-data/pdf/RDA0000/AOA0000C301.pdf"
			(at 0 0 90)
			(layer "F.Fab")
			(hide yes)
			(effects
				(font
					(size 1.27 1.27)
					(thickness 0.15)
				)
			)
		)
		(property "Author" "Antmicro"
			(at 189.6 -14.3 0)
			(layer "F.Fab")
			(hide yes)
			(effects
				(font
					(size 1 1)
					(thickness 0.15)
				)
			)
		)
		(property "Current" "1A"
			(at 189.6 -14.3 0)
			(layer "F.Fab")
			(hide yes)
			(effects
				(font
					(size 1 1)
					(thickness 0.15)
				)
			)
		)
		(property "License" "Apache-2.0"
			(at 189.6 -14.3 0)
			(layer "F.Fab")
			(hide yes)
			(effects
				(font
					(size 1 1)
					(thickness 0.15)
				)
			)
		)
		(property "MPN" "ERJ2GE0R00X"
			(at 189.6 -14.3 0)
			(layer "F.Fab")
			(hide yes)
			(effects
				(font
					(size 1 1)
					(thickness 0.15)
				)
			)
		)
		(property "Manufacturer" "Panasonic"
			(at 189.6 -14.3 0)
			(layer "F.Fab")
			(hide yes)
			(effects
				(font
					(size 1 1)
					(thickness 0.15)
				)
			)
		)
		(property "Tolerance" ""
			(at 189.6 -14.3 0)
			(layer "F.Fab")
			(hide yes)
			(effects
				(font
					(size 1 1)
					(thickness 0.15)
				)
			)
		)
		(property "Val" "0R"
			(at 189.6 -14.3 0)
			(layer "F.Fab")
			(hide yes)
			(effects
				(font
					(size 1 1)
					(thickness 0.15)
				)
			)
		)
		(sheetname "HDMI")
		(sheetfile "hdmi.kicad_sch")
		(attr smd)
		(fp_rect
			(start -0.925 -0.47)
			(end 0.925 0.47)
			(stroke
				(width 0.05)
				(type default)
			)
			(fill none)
			(layer "F.CrtYd")
		)
		(fp_rect
			(start -0.5 -0.25)
			(end 0.5 0.25)
			(stroke
				(width 0.15)
				(type solid)
			)
			(fill none)
			(layer "F.Fab")
		)
		(fp_text user "${REFERENCE}"
			(at -0.95 3.168 90)
			(layer "F.Fab")
			(hide yes)
			(effects
				(font
					(size 0.7 0.7)
					(thickness 0.15)
				)
				(justify left bottom)
			)
		)
		(fp_text user "License: Apache-2.0"
			(at -0.95 5.169 90)
			(layer "F.Fab")
			(hide yes)
			(effects
				(font
					(size 0.7 0.7)
					(thickness 0.15)
				)
				(justify left bottom)
			)
		)
		(fp_text user "Author: Antmicro"
			(at -0.95 4.169 90)
			(layer "F.Fab")
			(hide yes)
			(effects
				(font
					(size 0.7 0.7)
					(thickness 0.15)
				)
				(justify left bottom)
			)
		)
		(pad "1" smd roundrect
			(at -0.48 0 90)
			(size 0.59 0.64)
			(layers "F.Cu" "F.Paste" "F.Mask")
			(roundrect_rratio 0.25)
			(net 621 "Net-(Q1-S)")
			(pintype "passive")
		)
		(pad "2" smd roundrect
			(at 0.48 0 90)
			(size 0.59 0.64)
			(layers "F.Cu" "F.Paste" "F.Mask")
			(roundrect_rratio 0.25)
			(net 428 "DP1_HPD")
			(pintype "passive")
		)
	)
	(footprint "antmicro-footprints:C_0402_1005Metric"
		(layer "F.Cu")
		(at 89.3 116.05 -90)
		(descr "Capacitor SMD 0402")
		(tags "capacitor SMD 0402")
		(property "Reference" "C163"
			(at 0.24 0.53 -90)
			(layer "F.SilkS")
			(effects
				(font
					(size 0.7 0.7)
					(thickness 0.15)
				)
				(justify left bottom)
			)
		)
		(property "Value" "C_100n_0402"
			(at 0 1.4 -90)
			(layer "F.Fab")
			(effects
				(font
					(size 0.7 0.7)
					(thickness 0.15)
				)
				(justify left bottom)
			)
		)
		(property "Footprint" "antmicro-footprints:C_0402_1005Metric"
			(at 0 0 -90)
			(layer "F.Fab")
			(hide yes)
			(effects
				(font
					(size 1.27 1.27)
					(thickness 0.15)
				)
			)
		)
		(property "Datasheet" "https://www.murata.com/products/productdetail?partno=GRM155R61H104KE14%23"
			(at 0 0 -90)
			(layer "F.Fab")
			(hide yes)
			(effects
				(font
					(size 1.27 1.27)
					(thickness 0.15)
				)
			)
		)
		(property "Author" "Antmicro"
			(at -26.75 205.35 0)
			(layer "F.Fab")
			(hide yes)
			(effects
				(font
					(size 1 1)
					(thickness 0.15)
				)
			)
		)
		(property "Dielectric" "X5R"
			(at -26.75 205.35 0)
			(layer "F.Fab")
			(hide yes)
			(effects
				(font
					(size 1 1)
					(thickness 0.15)
				)
			)
		)
		(property "License" "Apache-2.0"
			(at -26.75 205.35 0)
			(layer "F.Fab")
			(hide yes)
			(effects
				(font
					(size 1 1)
					(thickness 0.15)
				)
			)
		)
		(property "MPN" "GRM155R61H104KE14D"
			(at -26.75 205.35 0)
			(layer "F.Fab")
			(hide yes)
			(effects
				(font
					(size 1 1)
					(thickness 0.15)
				)
			)
		)
		(property "Manufacturer" "Murata"
			(at -26.75 205.35 0)
			(layer "F.Fab")
			(hide yes)
			(effects
				(font
					(size 1 1)
					(thickness 0.15)
				)
			)
		)
		(property "Val" "100n"
			(at -26.75 205.35 0)
			(layer "F.Fab")
			(hide yes)
			(effects
				(font
					(size 1 1)
					(thickness 0.15)
				)
			)
		)
		(property "Voltage" "50V"
			(at -26.75 205.35 0)
			(layer "F.Fab")
			(hide yes)
			(effects
				(font
					(size 1 1)
					(thickness 0.15)
				)
			)
		)
		(sheetname "HDMI")
		(sheetfile "hdmi.kicad_sch")
		(attr smd)
		(fp_rect
			(start -0.925 -0.47)
			(end 0.925 0.47)
			(stroke
				(width 0.05)
				(type default)
			)
			(fill none)
			(layer "F.CrtYd")
		)
		(fp_line
			(start -0.494 0.248)
			(end -0.494 -0.25)
			(stroke
				(width 0.15)
				(type solid)
			)
			(layer "F.Fab")
		)
		(fp_line
			(start 0.504 0.248)
			(end -0.494 0.248)
			(stroke
				(width 0.15)
				(type solid)
			)
			(layer "F.Fab")
		)
		(fp_line
			(start -0.494 -0.25)
			(end 0.504 -0.25)
			(stroke
				(width 0.15)
				(type solid)
			)
			(layer "F.Fab")
		)
		(fp_line
			(start 0.504 -0.25)
			(end 0.504 0.248)
			(stroke
				(width 0.15)
				(type solid)
			)
			(layer "F.Fab")
		)
		(fp_text user "Author: Antmicro"
			(at -0.932 4.17 -90)
			(layer "F.Fab")
			(hide yes)
			(effects
				(font
					(size 0.7 0.7)
					(thickness 0.15)
				)
				(justify left bottom)
			)
		)
		(fp_text user "${REFERENCE}"
			(at -0.932 3.168 -90)
			(layer "F.Fab")
			(hide yes)
			(effects
				(font
					(size 0.7 0.7)
					(thickness 0.15)
				)
				(justify left bottom)
			)
		)
		(fp_text user "License: Apache-2.0"
			(at -0.932 5.17 -90)
			(layer "F.Fab")
			(hide yes)
			(effects
				(font
					(size 0.7 0.7)
					(thickness 0.15)
				)
				(justify left bottom)
			)
		)
		(pad "1" smd roundrect
			(at -0.48 0 270)
			(size 0.59 0.64)
			(layers "F.Cu" "F.Paste" "F.Mask")
			(roundrect_rratio 0.25)
			(net 1 "GND")
			(pintype "passive")
		)
		(pad "2" smd roundrect
			(at 0.48 0 270)
			(size 0.59 0.64)
			(layers "F.Cu" "F.Paste" "F.Mask")
			(roundrect_rratio 0.25)
			(net 87 "+3V3")
			(pintype "passive")
		)
	)
	(footprint "antmicro-footprints:C_0603_1608Metric"
		(layer "F.Cu")
		(at 87.75 120.8 180)
		(descr "Capacitor SMD 0603")
		(tags "capacitor 0603")
		(property "Reference" "C51"
			(at 1.825 -1.5 180)
			(layer "F.SilkS")
			(effects
				(font
					(size 0.7 0.7)
					(thickness 0.15)
				)
				(justify left bottom)
			)
		)
		(property "Value" "C_10u_0603"
			(at 0 1.6 180)
			(layer "F.Fab")
			(effects
				(font
					(size 0.7 0.7)
					(thickness 0.15)
				)
				(justify left bottom)
			)
		)
		(property "Footprint" "antmicro-footprints:C_0603_1608Metric"
			(at 0 0 180)
			(layer "F.Fab")
			(hide yes)
			(effects
				(font
					(size 1.27 1.27)
					(thickness 0.15)
				)
			)
		)
		(property "Datasheet" "https://www.murata.com/products/productdetail?partno=GRM188R61A106KE69%23"
			(at 0 0 180)
			(layer "F.Fab")
			(hide yes)
			(effects
				(font
					(size 1.27 1.27)
					(thickness 0.15)
				)
			)
		)
		(property "Author" "Antmicro"
			(at 175.5 241.6 0)
			(layer "F.Fab")
			(hide yes)
			(effects
				(font
					(size 1 1)
					(thickness 0.15)
				)
			)
		)
		(property "Dielectric" "template_dielectric"
			(at 175.5 241.6 0)
			(layer "F.Fab")
			(hide yes)
			(effects
				(font
					(size 1 1)
					(thickness 0.15)
				)
			)
		)
		(property "License" "Apache-2.0"
			(at 175.5 241.6 0)
			(layer "F.Fab")
			(hide yes)
			(effects
				(font
					(size 1 1)
					(thickness 0.15)
				)
			)
		)
		(property "MPN" "GRM188R61A106KE69D"
			(at 175.5 241.6 0)
			(layer "F.Fab")
			(hide yes)
			(effects
				(font
					(size 1 1)
					(thickness 0.15)
				)
			)
		)
		(property "Manufacturer" "Murata"
			(at 175.5 241.6 0)
			(layer "F.Fab")
			(hide yes)
			(effects
				(font
					(size 1 1)
					(thickness 0.15)
				)
			)
		)
		(property "Val" "10u"
			(at 175.5 241.6 0)
			(layer "F.Fab")
			(hide yes)
			(effects
				(font
					(size 1 1)
					(thickness 0.15)
				)
			)
		)
		(property "Voltage" ""
			(at 175.5 241.6 0)
			(layer "F.Fab")
			(hide yes)
			(effects
				(font
					(size 1 1)
					(thickness 0.15)
				)
			)
		)
		(sheetname "HDMI")
		(sheetfile "hdmi.kicad_sch")
		(attr smd)
		(fp_line
			(start -0.15 0.4)
			(end 0.15 0.4)
			(stroke
				(width 0.15)
				(type solid)
			)
			(layer "F.SilkS")
		)
		(fp_line
			(start -0.15 -0.4)
			(end 0.15 -0.4)
			(stroke
				(width 0.15)
				(type solid)
			)
			(layer "F.SilkS")
		)
		(fp_rect
			(start -1.25 -0.65)
			(end 1.25 0.65)
			(stroke
				(width 0.05)
				(type solid)
			)
			(fill none)
			(layer "F.CrtYd")
		)
		(fp_rect
			(start -0.8 -0.4)
			(end 0.8 0.4)
			(stroke
				(width 0.15)
				(type solid)
			)
			(fill none)
			(layer "F.Fab")
		)
		(fp_text user "Author: Antmicro"
			(at -1.682 4.894 180)
			(layer "F.Fab")
			(hide yes)
			(effects
				(font
					(size 0.7 0.7)
					(thickness 0.15)
				)
				(justify left bottom)
			)
		)
		(fp_text user "License: Apache-2.0"
			(at -1.682 5.895 180)
			(layer "F.Fab")
			(hide yes)
			(effects
				(font
					(size 0.7 0.7)
					(thickness 0.15)
				)
				(justify left bottom)
			)
		)
		(fp_text user "${REFERENCE}"
			(at -1.682 3.895 180)
			(layer "F.Fab")
			(hide yes)
			(effects
				(font
					(size 0.7 0.7)
					(thickness 0.15)
				)
				(justify left bottom)
			)
		)
		(pad "1" smd roundrect
			(at -0.7 0 180)
			(size 0.8 1)
			(layers "F.Cu" "F.Paste" "F.Mask")
			(roundrect_rratio 0.2)
			(net 498 "/HDMI/5V_HDMI")
			(pintype "passive")
		)
		(pad "2" smd roundrect
			(at 0.7 0 180)
			(size 0.8 1)
			(layers "F.Cu" "F.Paste" "F.Mask")
			(roundrect_rratio 0.2)
			(net 1 "GND")
			(pintype "passive")
		)
	)
	(footprint "antmicro-footprints:R_Array_4x0201_Panasonic_EXB18V"
		(layer "F.Cu")
		(at 93.625 118.3)
		(property "Reference" "R34"
			(at -1.05 -0.7 180)
			(layer "F.SilkS")
			(effects
				(font
					(size 0.7 0.7)
					(thickness 0.15)
				)
				(justify left bottom)
			)
		)
		(property "Value" "R_4x0R_0201_array"
			(at -1.1 1.8 0)
			(layer "F.Fab")
			(effects
				(font
					(size 0.7 0.7)
					(thickness 0.15)
				)
				(justify left bottom)
			)
		)
		(property "Footprint" "antmicro-footprints:R_Array_4x0201_Panasonic_EXB18V"
			(at 0 0 0)
			(layer "F.Fab")
			(hide yes)
			(effects
				(font
					(size 1.27 1.27)
					(thickness 0.15)
				)
			)
		)
		(property "Datasheet" "http://industrial.panasonic.com/cdbs/www-data/pdf/AOC0000/AOC0000C14.pdf"
			(at 0 0 0)
			(layer "F.Fab")
			(hide yes)
			(effects
				(font
					(size 1.27 1.27)
					(thickness 0.15)
				)
			)
		)
		(property "Author" "Antmicro"
			(at 0 0 0)
			(layer "F.Fab")
			(hide yes)
			(effects
				(font
					(size 1 1)
					(thickness 0.15)
				)
			)
		)
		(property "License" "Apache-2.0"
			(at 0 0 0)
			(layer "F.Fab")
			(hide yes)
			(effects
				(font
					(size 1 1)
					(thickness 0.15)
				)
			)
		)
		(property "MPN" "EXB-18VR000X"
			(at 0 0 0)
			(layer "F.Fab")
			(hide yes)
			(effects
				(font
					(size 1 1)
					(thickness 0.15)
				)
			)
		)
		(property "Manufacturer" "Panasonic"
			(at 0 0 0)
			(layer "F.Fab")
			(hide yes)
			(effects
				(font
					(size 1 1)
					(thickness 0.15)
				)
			)
		)
		(property "Val" "4x0R_0201"
			(at 0 0 0)
			(layer "F.Fab")
			(hide yes)
			(effects
				(font
					(size 1 1)
					(thickness 0.15)
				)
			)
		)
		(sheetname "HDMI")
		(sheetfile "hdmi.kicad_sch")
		(attr smd)
		(fp_line
			(start -0.8 -0.45)
			(end -0.8 0.45)
			(stroke
				(width 0.12)
				(type solid)
			)
			(layer "F.SilkS")
		)
		(fp_line
			(start 0.8 -0.45)
			(end 0.8 0.45)
			(stroke
				(width 0.12)
				(type solid)
			)
			(layer "F.SilkS")
		)
		(fp_rect
			(start -0.898 -0.66)
			(end 0.898 0.65)
			(stroke
				(width 0.05)
				(type solid)
			)
			(fill none)
			(layer "F.CrtYd")
		)
		(fp_text user "License: Apache-2.0"
			(at -1.051 6 0)
			(layer "F.Fab")
			(hide yes)
			(effects
				(font
					(size 0.7 0.7)
					(thickness 0.15)
				)
				(justify left bottom)
			)
		)
		(fp_text user "${REFERENCE}"
			(at -1.051 3.2 0)
			(layer "F.Fab")
			(hide yes)
			(effects
				(font
					(size 0.7 0.7)
					(thickness 0.15)
				)
				(justify left bottom)
			)
		)
		(fp_text user "Author: Antmicro"
			(at -1.051 4.599 0)
			(layer "F.Fab")
			(hide yes)
			(effects
				(font
					(size 0.7 0.7)
					(thickness 0.15)
				)
				(justify left bottom)
			)
		)
		(pad "1" smd roundrect
			(at -0.6 0.298)
			(size 0.2 0.4)
			(layers "F.Cu" "F.Paste" "F.Mask")
			(roundrect_rratio 0.25)
			(net 521 "/HDMI/HDMI_CLK_CONN_N")
			(pinfunction "R1.1")
			(pintype "passive")
		)
		(pad "2" smd roundrect
			(at -0.202 0.298)
			(size 0.2 0.4)
			(layers "F.Cu" "F.Paste" "F.Mask")
			(roundrect_rratio 0.25)
			(net 522 "/HDMI/HDMI_CLK_CONN_P")
			(pinfunction "R2.1")
			(pintype "passive")
		)
		(pad "3" smd roundrect
			(at 0.2 0.298)
			(size 0.2 0.4)
			(layers "F.Cu" "F.Paste" "F.Mask")
			(roundrect_rratio 0.25)
			(net 523 "/HDMI/HDMI_D0_CONN_N")
			(pinfunction "R3.1")
			(pintype "passive")
		)
		(pad "4" smd roundrect
			(at 0.598 0.298)
			(size 0.2 0.4)
			(layers "F.Cu" "F.Paste" "F.Mask")
			(roundrect_rratio 0.25)
			(net 524 "/HDMI/HDMI_D0_CONN_P")
			(pinfunction "R4.1")
			(pintype "passive")
		)
		(pad "5" smd roundrect
			(at 0.598 -0.3)
			(size 0.2 0.4)
			(layers "F.Cu" "F.Paste" "F.Mask")
			(roundrect_rratio 0.25)
			(net 494 "/HDMI/HDMI_D0_P")
			(pinfunction "R4.2")
			(pintype "passive")
		)
		(pad "6" smd roundrect
			(at 0.2 -0.3)
			(size 0.2 0.4)
			(layers "F.Cu" "F.Paste" "F.Mask")
			(roundrect_rratio 0.25)
			(net 488 "/HDMI/HDMI_D0_N")
			(pinfunction "R3.2")
			(pintype "passive")
		)
		(pad "7" smd roundrect
			(at -0.202 -0.3)
			(size 0.2 0.4)
			(layers "F.Cu" "F.Paste" "F.Mask")
			(roundrect_rratio 0.25)
			(net 495 "/HDMI/HDMI_CLK_P")
			(pinfunction "R2.2")
			(pintype "passive")
		)
		(pad "8" smd roundrect
			(at -0.6 -0.3)
			(size 0.2 0.4)
			(layers "F.Cu" "F.Paste" "F.Mask")
			(roundrect_rratio 0.25)
			(net 489 "/HDMI/HDMI_CLK_N")
			(pinfunction "R1.2")
			(pintype "passive")
		)
	)
)
